(kicad_pcb
	(version 20260206)
	(generator "pcbnew")
	(generator_version "10.0")
	(general
		(thickness 1.6)
		(legacy_teardrops no)
	)
	(paper "A4")
	(title_block
		(title "Bryce Canyon_F.DPB_16315-1-OCP.brd")
		(comment 1 "Bryce Canyon / footprints 559-562 of 2223")
	)
	(layers
		(0 "F.Cu" signal "TOP")
		(4 "In1.Cu" signal "L2GND")
		(6 "In2.Cu" signal "L3")
		(8 "In3.Cu" signal "L4GND")
		(10 "In4.Cu" signal "L5")
		(12 "In5.Cu" signal "L6VCC")
		(14 "In6.Cu" signal "L7VCC")
		(16 "In7.Cu" signal "L8")
		(18 "In8.Cu" signal "L9GND")
		(20 "In9.Cu" signal "L10")
		(22 "In10.Cu" signal "L11GND")
		(2 "B.Cu" signal "BOTTOM")
		(9 "F.Adhes" user "F.Adhesive")
		(11 "B.Adhes" user "B.Adhesive")
		(13 "F.Paste" user "Package Geometry/Pastemask Top")
		(15 "B.Paste" user "Package Geometry/Pastemask Bottom")
		(5 "F.SilkS" user "Ref Des/Silkscreen Top")
		(7 "B.SilkS" user "Ref Des/Silkscreen Bottom")
		(1 "F.Mask" user "Board Geometry/Soldermask Top")
		(3 "B.Mask" user "Board Geometry/Soldermask Bottom")
		(17 "Dwgs.User" user "User.Drawings")
		(19 "Cmts.User" user "User.Comments")
		(21 "Eco1.User" user "User.Eco1")
		(23 "Eco2.User" user "User.Eco2")
		(25 "Edge.Cuts" user "Board Geometry/Outline")
		(27 "Margin" user)
		(31 "F.CrtYd" user "Package Geometry/Place Bound Top")
		(29 "B.CrtYd" user "Package Geometry/Place Bound Bottom")
		(35 "F.Fab" user "Ref Des/Assembly Top")
		(33 "B.Fab" user "Ref Des/Assembly Bottom")
	)
	(footprint ""
		(layer "F.Cu")
		(at 153.232866 -137.879074 -90)
		(property "Reference" "R1078"
			(at 0 0 270)
			(layer "F.SilkS")
			(hide yes)
			(effects
				(font
					(size 1.27 1.27)
				)
			)
		)
		(property "Value" "10R2F-L-GP"
			(at 0.064008 -3.993896 270)
			(unlocked yes)
			(layer "F.Fab")
			(hide yes)
			(effects
				(font
					(size 1.016 1.016)
					(thickness 0.1524)
				)
			)
		)
		(property "Device Type" "R402H14"
			(at 0.064008 -5.517896 270)
			(unlocked yes)
			(layer "F.Fab")
			(hide yes)
			(effects
				(font
					(size 1.016 1.016)
					(thickness 0.1524)
				)
			)
		)
		(duplicate_pad_numbers_are_jumpers no)
		(fp_line
			(start -0.508 -0.9398)
			(end -0.508 0.9398)
			(stroke
				(width 0.1524)
				(type default)
			)
			(layer "F.SilkS")
		)
		(fp_line
			(start 0.508 -0.9398)
			(end -0.508 -0.9398)
			(stroke
				(width 0.1524)
				(type default)
			)
			(layer "F.SilkS")
		)
		(fp_rect
			(start -0.508 0.9398)
			(end 0.508 -0.9398)
			(stroke
				(width 0)
				(type default)
			)
			(fill no)
			(layer "F.CrtYd")
		)
		(fp_rect
			(start -0.508 0.9398)
			(end 0.508 -0.9398)
			(stroke
				(width 0)
				(type default)
			)
			(fill no)
			(layer "F.Fab")
		)
		(pad "1" smd custom
			(at 0 -0.4445 270)
			(size 0.1397 0.1397)
			(layers "F.Cu" "F.Mask" "F.Paste")
			(net "MB0_CM_SENSE_R1_P")
			(options
				(clearance outline)
				(anchor circle)
			)
			(primitives
				(gr_poly
					(pts
						(arc
							(start -0.1778 -0.2794)
							(mid -0.249642 -0.249642)
							(end -0.2794 -0.1778)
						)
						(arc
							(start -0.2794 0.1778)
							(mid -0.249642 0.249642)
							(end -0.1778 0.2794)
						)
						(arc
							(start 0.1778 0.2794)
							(mid 0.249642 0.249642)
							(end 0.2794 0.1778)
						)
						(arc
							(start 0.2794 -0.1778)
							(mid 0.249642 -0.249642)
							(end 0.1778 -0.2794)
						)
					)
					(width 0)
					(fill yes)
				)
			)
		)
		(pad "2" smd custom
			(at 0 0.4445 270)
			(size 0.1397 0.1397)
			(layers "F.Cu" "F.Mask" "F.Paste")
			(net "MB0_HS_SENSE_P")
			(options
				(clearance outline)
				(anchor circle)
			)
			(primitives
				(gr_poly
					(pts
						(arc
							(start -0.1778 -0.2794)
							(mid -0.249642 -0.249642)
							(end -0.2794 -0.1778)
						)
						(arc
							(start -0.2794 0.1778)
							(mid -0.249642 0.249642)
							(end -0.1778 0.2794)
						)
						(arc
							(start 0.1778 0.2794)
							(mid 0.249642 0.249642)
							(end 0.2794 0.1778)
						)
						(arc
							(start 0.2794 -0.1778)
							(mid 0.249642 -0.249642)
							(end 0.1778 -0.2794)
						)
					)
					(width 0)
					(fill yes)
				)
			)
		)
	)
	(footprint ""
		(layer "F.Cu")
		(at 230.7844 -383.0574 -90)
		(property "Reference" "R1144"
			(at 0 0 270)
			(layer "F.SilkS")
			(hide yes)
			(effects
				(font
					(size 1.27 1.27)
				)
			)
		)
		(property "Value" "0R2J-2-GP"
			(at 0.064008 -3.993896 270)
			(unlocked yes)
			(layer "F.Fab")
			(hide yes)
			(effects
				(font
					(size 1.016 1.016)
					(thickness 0.1524)
				)
			)
		)
		(property "Device Type" "R402H16"
			(at 0.064008 -5.517896 270)
			(unlocked yes)
			(layer "F.Fab")
			(hide yes)
			(effects
				(font
					(size 1.016 1.016)
					(thickness 0.1524)
				)
			)
		)
		(duplicate_pad_numbers_are_jumpers no)
		(fp_line
			(start -0.508 -0.9398)
			(end -0.508 0.9398)
			(stroke
				(width 0.1524)
				(type default)
			)
			(layer "F.SilkS")
		)
		(fp_line
			(start 0.508 -0.9398)
			(end -0.508 -0.9398)
			(stroke
				(width 0.1524)
				(type default)
			)
			(layer "F.SilkS")
		)
		(fp_rect
			(start -0.508 0.9398)
			(end 0.508 -0.9398)
			(stroke
				(width 0)
				(type default)
			)
			(fill no)
			(layer "F.CrtYd")
		)
		(fp_rect
			(start -0.508 0.9398)
			(end 0.508 -0.9398)
			(stroke
				(width 0)
				(type default)
			)
			(fill no)
			(layer "F.Fab")
		)
		(pad "1" smd custom
			(at 0 -0.4445 270)
			(size 0.1397 0.1397)
			(layers "F.Cu" "F.Mask" "F.Paste")
			(net "MB3_SCL_R")
			(options
				(clearance outline)
				(anchor circle)
			)
			(primitives
				(gr_poly
					(pts
						(arc
							(start -0.1778 -0.2794)
							(mid -0.249642 -0.249642)
							(end -0.2794 -0.1778)
						)
						(arc
							(start -0.2794 0.1778)
							(mid -0.249642 0.249642)
							(end -0.1778 0.2794)
						)
						(arc
							(start 0.1778 0.2794)
							(mid 0.249642 0.249642)
							(end 0.2794 0.1778)
						)
						(arc
							(start 0.2794 -0.1778)
							(mid 0.249642 -0.249642)
							(end 0.1778 -0.2794)
						)
					)
					(width 0)
					(fill yes)
				)
			)
		)
		(pad "2" smd custom
			(at 0 0.4445 270)
			(size 0.1397 0.1397)
			(layers "F.Cu" "F.Mask" "F.Paste")
			(net "I2C_DPB_A_SCL_BUF")
			(options
				(clearance outline)
				(anchor circle)
			)
			(primitives
				(gr_poly
					(pts
						(arc
							(start -0.1778 -0.2794)
							(mid -0.249642 -0.249642)
							(end -0.2794 -0.1778)
						)
						(arc
							(start -0.2794 0.1778)
							(mid -0.249642 0.249642)
							(end -0.1778 0.2794)
						)
						(arc
							(start 0.1778 0.2794)
							(mid 0.249642 0.249642)
							(end 0.2794 0.1778)
						)
						(arc
							(start 0.2794 -0.1778)
							(mid 0.249642 -0.249642)
							(end 0.1778 -0.2794)
						)
					)
					(width 0)
					(fill yes)
				)
			)
		)
	)
	(footprint ""
		(layer "F.Cu")
		(at 219.878402 -213.754462)
		(property "Reference" "C57"
			(at 0 0 0)
			(layer "F.SilkS")
			(hide yes)
			(effects
				(font
					(size 1.27 1.27)
				)
			)
		)
		(property "Value" "SC1U16V3KX-5GP"
			(at 0 -2.8194 0)
			(unlocked yes)
			(layer "F.Fab")
			(hide yes)
			(effects
				(font
					(size 1.016 1.016)
					(thickness 0.1524)
				)
			)
		)
		(property "Device Type" "C603H36"
			(at 0 -4.3434 0)
			(unlocked yes)
			(layer "F.Fab")
			(hide yes)
			(effects
				(font
					(size 1.016 1.016)
					(thickness 0.1524)
				)
			)
		)
		(duplicate_pad_numbers_are_jumpers no)
		(fp_line
			(start 0.508 0)
			(end -0.508 0)
			(stroke
				(width 0.2032)
				(type default)
			)
			(layer "F.SilkS")
		)
		(fp_rect
			(start -0.5842 1.3335)
			(end 0.5842 -1.3335)
			(stroke
				(width 0)
				(type default)
			)
			(fill no)
			(layer "F.CrtYd")
		)
		(fp_rect
			(start -0.5842 1.3335)
			(end 0.5842 -1.3335)
			(stroke
				(width 0)
				(type default)
			)
			(fill no)
			(layer "F.Fab")
		)
		(pad "1" smd custom
			(at 0 -0.762)
			(size 0.2159 0.2159)
			(layers "F.Cu" "F.Mask" "F.Paste")
			(net "P3V3_STBY_A")
			(options
				(clearance outline)
				(anchor circle)
			)
			(primitives
				(gr_poly
					(pts
						(arc
							(start -0.3302 -0.4318)
							(mid -0.402042 -0.402042)
							(end -0.4318 -0.3302)
						)
						(arc
							(start -0.4318 0.3302)
							(mid -0.402042 0.402042)
							(end -0.3302 0.4318)
						)
						(arc
							(start 0.3302 0.4318)
							(mid 0.402042 0.402042)
							(end 0.4318 0.3302)
						)
						(arc
							(start 0.4318 -0.3302)
							(mid 0.402042 -0.402042)
							(end 0.3302 -0.4318)
						)
					)
					(width 0)
					(fill yes)
				)
			)
		)
		(pad "2" smd custom
			(at 0 0.762)
			(size 0.2159 0.2159)
			(layers "F.Cu" "F.Mask" "F.Paste")
			(net "GND")
			(options
				(clearance outline)
				(anchor circle)
			)
			(primitives
				(gr_poly
					(pts
						(arc
							(start -0.3302 -0.4318)
							(mid -0.402042 -0.402042)
							(end -0.4318 -0.3302)
						)
						(arc
							(start -0.4318 0.3302)
							(mid -0.402042 0.402042)
							(end -0.3302 0.4318)
						)
						(arc
							(start 0.3302 0.4318)
							(mid 0.402042 0.402042)
							(end 0.4318 0.3302)
						)
						(arc
							(start 0.4318 -0.3302)
							(mid 0.402042 -0.402042)
							(end 0.3302 -0.4318)
						)
					)
					(width 0)
					(fill yes)
				)
			)
		)
	)
	(footprint ""
		(layer "F.Cu")
		(at 149.196298 -44.871894 -90)
		(property "Reference" "R785"
			(at 0 0 270)
			(layer "F.SilkS")
			(hide yes)
			(effects
				(font
					(size 1.27 1.27)
				)
			)
		)
		(property "Value" "0R2J-2-GP"
			(at 0.064008 -3.993896 270)
			(unlocked yes)
			(layer "F.Fab")
			(hide yes)
			(effects
				(font
					(size 1.016 1.016)
					(thickness 0.1524)
				)
			)
		)
		(property "Device Type" "R402H16"
			(at 0.064008 -5.517896 270)
			(unlocked yes)
			(layer "F.Fab")
			(hide yes)
			(effects
				(font
					(size 1.016 1.016)
					(thickness 0.1524)
				)
			)
		)
		(duplicate_pad_numbers_are_jumpers no)
		(fp_line
			(start -0.508 -0.9398)
			(end -0.508 0.9398)
			(stroke
				(width 0.1524)
				(type default)
			)
			(layer "F.SilkS")
		)
		(fp_line
			(start 0.508 -0.9398)
			(end -0.508 -0.9398)
			(stroke
				(width 0.1524)
				(type default)
			)
			(layer "F.SilkS")
		)
		(fp_rect
			(start -0.508 0.9398)
			(end 0.508 -0.9398)
			(stroke
				(width 0)
				(type default)
			)
			(fill no)
			(layer "F.CrtYd")
		)
		(fp_rect
			(start -0.508 0.9398)
			(end 0.508 -0.9398)
			(stroke
				(width 0)
				(type default)
			)
			(fill no)
			(layer "F.Fab")
		)
		(pad "1" smd custom
			(at 0 -0.4445 270)
			(size 0.1397 0.1397)
			(layers "F.Cu" "F.Mask" "F.Paste")
			(net "DRIVE_A_28_PWR")
			(options
				(clearance outline)
				(anchor circle)
			)
			(primitives
				(gr_poly
					(pts
						(arc
							(start -0.1778 -0.2794)
							(mid -0.249642 -0.249642)
							(end -0.2794 -0.1778)
						)
						(arc
							(start -0.2794 0.1778)
							(mid -0.249642 0.249642)
							(end -0.1778 0.2794)
						)
						(arc
							(start 0.1778 0.2794)
							(mid 0.249642 0.249642)
							(end 0.2794 0.1778)
						)
						(arc
							(start 0.2794 -0.1778)
							(mid 0.249642 -0.249642)
							(end 0.1778 -0.2794)
						)
					)
					(width 0)
					(fill yes)
				)
			)
		)
		(pad "2" smd custom
			(at 0 0.4445 270)
			(size 0.1397 0.1397)
			(layers "F.Cu" "F.Mask" "F.Paste")
			(net "SW_PWR_R_HDD28")
			(options
				(clearance outline)
				(anchor circle)
			)
			(primitives
				(gr_poly
					(pts
						(arc
							(start -0.1778 -0.2794)
							(mid -0.249642 -0.249642)
							(end -0.2794 -0.1778)
						)
						(arc
							(start -0.2794 0.1778)
							(mid -0.249642 0.249642)
							(end -0.1778 0.2794)
						)
						(arc
							(start 0.1778 0.2794)
							(mid 0.249642 0.249642)
							(end 0.2794 0.1778)
						)
						(arc
							(start 0.2794 -0.1778)
							(mid 0.249642 -0.249642)
							(end 0.1778 -0.2794)
						)
					)
					(width 0)
					(fill yes)
				)
			)
		)
	)
)
